FILE_TYPE = MACRO_DRAWING;
SET COLOR_WIRE YELLOW;
SET COLOR_PROP ORANGE;
SET COLOR_DOT WHITE;
SET COLOR_ARC YELLOW;
SET COLOR_BODY GREEN;
SET COLOR_NOTE PURPLE;
SET PROP_DISPLAY VALUE;
SET PAGE_NUMBER P119;
FORCEADD QUANTA_TITLE_BLOCK_C..1
(100 -425);
FORCEPROP 1 LAST CUSTOM_TXT_CDS <NAME_2>
J 0
(-3075 -375);
FORCEPROP 1 LAST CUSTOM_TXT_CDS <NAME_1>
J 0
(-3075 -250);
FORCEPROP 1 LAST CUSTOM_TXT_CDS <Q_NUMBER>
J 0
(-1303 -322);
DISPLAY 1.212766 (-1303 -322);
FORCEPROP 1 LAST CUSTOM_TXT_CDS <Q_PROJ>
J 0
(-2282 -323);
DISPLAY 1.212766 (-2282 -323);
FORCEPROP 1 LAST CUSTOM_TXT_CDS <Q_REV>
J 0
(-84 -322);
DISPLAY 1.212766 (-84 -322);
FORCEPROP 1 LAST CUSTOM_TXT_CDS <CON_LAST_MODIFIED>
J 0
(-1785 -410);
DISPLAY 0.978723 (-1785 -410);
FORCEPROP 1 LAST CUSTOM_TXT_CDS <CON_PAGE_NUM> OF <CON_TOTAL_PAGES>
J 0
(-346 -407);
DISPLAY 0.978723 (-346 -407);
FORCEPROP 1 LAST Q_DEPT BU9
J 1
(-3663 -376);
DISPLAY 1.957447 (-3663 -376);
PAINT GREEN (-3663 -376);
FORCEPROP 1 LAST Q_TITLE OCP 3.0 - SLOT
J 0
(-9225 -375);
DISPLAY 2.446809 (-9225 -375);
PAINT GREEN (-9225 -375);
FORCEPROP 2 LAST CDS_LIB pure_quanta
J 0
(100 -425);
DISPLAY INVISIBLE (100 -425);
FORCEPROP 1 LAST CDS_LMAN_SYM_OUTLINE -9475,6775,100,-125
J 0
(100 -425);
DISPLAY 0.468085 (100 -425);
PAINT GREEN (100 -425);
DISPLAY INVISIBLE (100 -425);
FORCEPROP 2 LAST PAGE_BORDER TRUE
J 0
(-7790 4825);
DISPLAY 0.638298 (-7790 4825);
PAINT PINK (-7790 4825);
DISPLAY INVISIBLE (-7790 4825);
FORCEPROP 1 LAST COMMENT_BODY TRUE
J 0
(112 -438);
DISPLAY 0.978723 (112 -438);
PAINT GREEN (112 -438);
DISPLAY INVISIBLE (112 -438);
FORCEPROP 2 LAST CDS_XR_PAGE_TITLE CR-119 : @T6G_MB_LIB.T6G(SCH_1):PAGE119
J 0
(-7790 4825);
DISPLAY 0.638298 (-7790 4825);
PAINT PINK (-7790 4825);
DISPLAY INVISIBLE (-7790 4825);
FORCEPROP 2 LAST CUSTOM_TXT_CDS <XR_PAGE_TITLE>
J 0
(-7790 4825);
DISPLAY 0.638298 (-7790 4825);
PAINT PINK (-7790 4825);
DISPLAY INVISIBLE (-7790 4825);
FORCEPROP 0 LAST CDS_CON_LAST_MODIFIED Wed Mar 09 17:52:28 2022
J 0
(-1785 -410);
DISPLAY INVISIBLE (-1785 -410);
QUIT
